# S9S_MB_2U (Grand Teton) — schematic netlist excerpt (pin names and nets, part order shuffled) for the footprints in the layout excerpt that follows; sources: Cadence DE-HDL packaged netlist, KiCad conversion of 03242023_DA0F0TMBIJ0_F0T_Motherboard_J_brd_V01_OCP.brd

R1117  Q_RES  6.19K 1% CHIP  pkg 0402LF  page 301 : A = MB0_P12V_STBY_PWRGD ; B = AGND_HSC
L19  Q_INDUCTOR  FCM2012KF-601T/0.5A IND  pkg SMLF  page 211 : \1\ = P3V3 ; \2\ = P3V3_9ZXL045
L14  Q_INDUCTOR  FCM2012KF-601T/0.5A IND  pkg SMLF  page 210 : \1\ = P3V3_AUX ; \2\ = P3V3_AUX_CLK_GEN_VDDMXCK_CK440

(kicad_pcb
	(version 20260206)
	(generator "pcbnew")
	(generator_version "10.0")
	(general
		(thickness 1.6)
		(legacy_teardrops no)
	)
	(paper "A4")
	(title_block
		(title "03242023_DA0F0TMBIJ0_F0T_Motherboard_J_brd_V01_OCP.brd")
		(comment 1 "Grand Teton / footprints 5453-5455 of 6105")
	)
	(layers
		(0 "F.Cu" signal "TOP")
		(4 "In1.Cu" signal "GND")
		(6 "In2.Cu" signal "IN1")
		(8 "In3.Cu" signal "GND1")
		(10 "In4.Cu" signal "IN2")
		(12 "In5.Cu" signal "GND2")
		(14 "In6.Cu" signal "IN3")
		(16 "In7.Cu" signal "GND3")
		(18 "In8.Cu" signal "VCC")
		(20 "In9.Cu" signal "VCC1")
		(22 "In10.Cu" signal "GND4")
		(24 "In11.Cu" signal "IN4")
		(26 "In12.Cu" signal "GND5")
		(28 "In13.Cu" signal "IN5")
		(30 "In14.Cu" signal "GND6")
		(32 "In15.Cu" signal "IN6")
		(34 "In16.Cu" signal "GND7")
		(2 "B.Cu" signal "BOTTOM")
		(9 "F.Adhes" user "F.Adhesive")
		(11 "B.Adhes" user "B.Adhesive")
		(13 "F.Paste" user "Package Geometry/Pastemask Top")
		(15 "B.Paste" user "Package Geometry/Pastemask Bottom")
		(5 "F.SilkS" user "Ref Des/Silkscreen Top")
		(7 "B.SilkS" user "Ref Des/Silkscreen Bottom")
		(1 "F.Mask" user "Board Geometry/Soldermask Top")
		(3 "B.Mask" user "Board Geometry/Soldermask Bottom")
		(17 "Dwgs.User" user "User.Drawings")
		(19 "Cmts.User" user "User.Comments")
		(21 "Eco1.User" user "User.Eco1")
		(23 "Eco2.User" user "User.Eco2")
		(25 "Edge.Cuts" user "Board Geometry/Outline")
		(27 "Margin" user)
		(31 "F.CrtYd" user "Package Geometry/Place Bound Top")
		(29 "B.CrtYd" user "Package Geometry/Place Bound Bottom")
		(35 "F.Fab" user "Ref Des/Assembly Top")
		(33 "B.Fab" user "Ref Des/Assembly Bottom")
	)
	(footprint ""
		(layer "B.Cu")
		(at 179.758848 -406.903682)
		(property "Reference" "R1117"
			(at 0 0 0)
			(layer "B.SilkS")
			(hide yes)
			(effects
				(font
					(size 1.27 1.27)
				)
				(justify mirror)
			)
		)
		(property "Value" ""
			(at 0 0 0)
			(layer "B.Fab")
			(effects
				(font
					(size 1.27 1.27)
				)
				(justify mirror)
			)
		)
		(duplicate_pad_numbers_are_jumpers no)
		(fp_line
			(start -0.7874 -0.4064)
			(end -0.7874 0.4064)
			(stroke
				(width 0.1524)
				(type default)
			)
			(layer "B.SilkS")
		)
		(fp_line
			(start -0.7874 0.4064)
			(end 0.7874 0.4064)
			(stroke
				(width 0.1524)
				(type default)
			)
			(layer "B.SilkS")
		)
		(fp_line
			(start 0.7874 -0.4064)
			(end -0.7874 -0.4064)
			(stroke
				(width 0.1524)
				(type default)
			)
			(layer "B.SilkS")
		)
		(fp_line
			(start 0.7874 0.4064)
			(end 0.7874 -0.4064)
			(stroke
				(width 0.1524)
				(type default)
			)
			(layer "B.SilkS")
		)
		(fp_line
			(start -0.67945 -0.3048)
			(end -0.67945 0.3048)
			(stroke
				(width 0.1)
				(type default)
			)
			(layer "B.Fab")
		)
		(fp_line
			(start -0.67945 0.3048)
			(end -0.120396 0.3048)
			(stroke
				(width 0.1)
				(type default)
			)
			(layer "B.Fab")
		)
		(fp_line
			(start -0.12065 -0.3048)
			(end -0.67945 -0.3048)
			(stroke
				(width 0.1)
				(type default)
			)
			(layer "B.Fab")
		)
		(fp_line
			(start -0.12065 -0.2794)
			(end -0.12065 -0.3048)
			(stroke
				(width 0.1)
				(type default)
			)
			(layer "B.Fab")
		)
		(fp_line
			(start -0.120396 0.2794)
			(end 0.12065 0.2794)
			(stroke
				(width 0.1)
				(type default)
			)
			(layer "B.Fab")
		)
		(fp_line
			(start -0.120396 0.3048)
			(end -0.120396 0.2794)
			(stroke
				(width 0.1)
				(type default)
			)
			(layer "B.Fab")
		)
		(fp_line
			(start 0.12065 -0.305054)
			(end 0.12065 -0.2794)
			(stroke
				(width 0.1)
				(type default)
			)
			(layer "B.Fab")
		)
		(fp_line
			(start 0.12065 -0.2794)
			(end -0.12065 -0.2794)
			(stroke
				(width 0.1)
				(type default)
			)
			(layer "B.Fab")
		)
		(fp_line
			(start 0.12065 0.2794)
			(end 0.12065 0.3048)
			(stroke
				(width 0.1)
				(type default)
			)
			(layer "B.Fab")
		)
		(fp_line
			(start 0.12065 0.3048)
			(end 0.67945 0.3048)
			(stroke
				(width 0.1)
				(type default)
			)
			(layer "B.Fab")
		)
		(fp_line
			(start 0.67945 -0.305054)
			(end 0.12065 -0.305054)
			(stroke
				(width 0.1)
				(type default)
			)
			(layer "B.Fab")
		)
		(fp_line
			(start 0.67945 0.3048)
			(end 0.67945 -0.305054)
			(stroke
				(width 0.1)
				(type default)
			)
			(layer "B.Fab")
		)
		(pad "1" smd circle
			(at 0.40005 0 180)
			(size 0 0)
			(layers "B.Cu" "B.Mask" "B.Paste")
			(net "MB0_P12V_STBY_PWRGD")
		)
		(pad "2" smd circle
			(at -0.40005 0 180)
			(size 0 0)
			(layers "B.Cu" "B.Mask" "B.Paste")
			(net "AGND_HSC")
		)
	)
	(footprint ""
		(layer "B.Cu")
		(at 261.694168 -103.101902)
		(property "Reference" "L14"
			(at 0 0 0)
			(layer "B.SilkS")
			(hide yes)
			(effects
				(font
					(size 1.27 1.27)
				)
				(justify mirror)
			)
		)
		(property "Value" ""
			(at 0 0 0)
			(layer "B.Fab")
			(effects
				(font
					(size 1.27 1.27)
				)
				(justify mirror)
			)
		)
		(duplicate_pad_numbers_are_jumpers no)
		(fp_line
			(start -1.63576 -0.8128)
			(end -1.63576 0.8128)
			(stroke
				(width 0.1524)
				(type default)
			)
			(layer "B.SilkS")
		)
		(fp_line
			(start -1.63576 0.8128)
			(end 1.63576 0.8128)
			(stroke
				(width 0.1524)
				(type default)
			)
			(layer "B.SilkS")
		)
		(fp_line
			(start 1.63576 -0.8128)
			(end -1.63576 -0.8128)
			(stroke
				(width 0.1524)
				(type default)
			)
			(layer "B.SilkS")
		)
		(fp_line
			(start 1.63576 -0.8128)
			(end 1.63576 0.8128)
			(stroke
				(width 0.1524)
				(type default)
			)
			(layer "B.SilkS")
		)
		(fp_line
			(start -1.560576 -0.738632)
			(end 1.56083 -0.738632)
			(stroke
				(width 0.1)
				(type default)
			)
			(layer "B.Fab")
		)
		(fp_line
			(start -1.560576 0.7366)
			(end -1.560576 -0.738632)
			(stroke
				(width 0.1)
				(type default)
			)
			(layer "B.Fab")
		)
		(fp_line
			(start -1.524 0.7366)
			(end -1.560576 0.7366)
			(stroke
				(width 0.1)
				(type default)
			)
			(layer "B.Fab")
		)
		(fp_line
			(start 1.524 0.7366)
			(end -1.524 0.7366)
			(stroke
				(width 0.1)
				(type default)
			)
			(layer "B.Fab")
		)
		(fp_line
			(start 1.56083 -0.738632)
			(end 1.56083 0.7366)
			(stroke
				(width 0.1)
				(type default)
			)
			(layer "B.Fab")
		)
		(fp_line
			(start 1.56083 0.7366)
			(end 1.524 0.7366)
			(stroke
				(width 0.1)
				(type default)
			)
			(layer "B.Fab")
		)
		(pad "1" smd rect
			(at 0.94996 0)
			(size 1.1176 1.3716)
			(layers "B.Cu" "B.Mask" "B.Paste")
			(net "P3V3_AUX")
		)
		(pad "2" smd rect
			(at -0.94996 0)
			(size 1.1176 1.3716)
			(layers "B.Cu" "B.Mask" "B.Paste")
			(net "P3V3_AUX_CLK_GEN_VDDMXCK_CK440")
		)
	)
	(footprint ""
		(layer "B.Cu")
		(at 105.11536 -417.399216 180)
		(property "Reference" "L19"
			(at 0 0 0)
			(layer "B.SilkS")
			(hide yes)
			(effects
				(font
					(size 1.27 1.27)
				)
				(justify mirror)
			)
		)
		(property "Value" ""
			(at 0 0 0)
			(layer "B.Fab")
			(effects
				(font
					(size 1.27 1.27)
				)
				(justify mirror)
			)
		)
		(duplicate_pad_numbers_are_jumpers no)
		(fp_line
			(start 1.63576 -0.8128)
			(end 1.63576 0.8128)
			(stroke
				(width 0.1524)
				(type default)
			)
			(layer "B.SilkS")
		)
		(fp_line
			(start 1.63576 -0.8128)
			(end -1.63576 -0.8128)
			(stroke
				(width 0.1524)
				(type default)
			)
			(layer "B.SilkS")
		)
		(fp_line
			(start -1.63576 0.8128)
			(end 1.63576 0.8128)
			(stroke
				(width 0.1524)
				(type default)
			)
			(layer "B.SilkS")
		)
		(fp_line
			(start -1.63576 -0.8128)
			(end -1.63576 0.8128)
			(stroke
				(width 0.1524)
				(type default)
			)
			(layer "B.SilkS")
		)
		(fp_line
			(start 1.56083 0.7366)
			(end 1.524 0.7366)
			(stroke
				(width 0.1)
				(type default)
			)
			(layer "B.Fab")
		)
		(fp_line
			(start 1.56083 -0.738632)
			(end 1.56083 0.7366)
			(stroke
				(width 0.1)
				(type default)
			)
			(layer "B.Fab")
		)
		(fp_line
			(start 1.524 0.7366)
			(end -1.524 0.7366)
			(stroke
				(width 0.1)
				(type default)
			)
			(layer "B.Fab")
		)
		(fp_line
			(start -1.524 0.7366)
			(end -1.560576 0.7366)
			(stroke
				(width 0.1)
				(type default)
			)
			(layer "B.Fab")
		)
		(fp_line
			(start -1.560576 0.7366)
			(end -1.560576 -0.738632)
			(stroke
				(width 0.1)
				(type default)
			)
			(layer "B.Fab")
		)
		(fp_line
			(start -1.560576 -0.738632)
			(end 1.56083 -0.738632)
			(stroke
				(width 0.1)
				(type default)
			)
			(layer "B.Fab")
		)
		(pad "1" smd rect
			(at 0.94996 0 180)
			(size 1.1176 1.3716)
			(layers "B.Cu" "B.Mask" "B.Paste")
			(net "P3V3")
		)
		(pad "2" smd rect
			(at -0.94996 0 180)
			(size 1.1176 1.3716)
			(layers "B.Cu" "B.Mask" "B.Paste")
			(net "P3V3_9ZXL045")
		)
	)
)
